# T6G (Grand Teton) — schematic netlist excerpt (pin names and nets, part order shuffled) for the footprints in the layout excerpt that follows; sources: Cadence DE-HDL packaged netlist, KiCad conversion of 04192023_DAF0TMB3IC0_F0TG_MB_C_brd_V02_OCP.brd

C567  Q_CAP  10UF 6.3V 20% X6S  pkg C0402  page 279 : A = P0V9_CPU0_RT0_2A ; B = GND
C245  Q_CAP  22UF 4V 20% X6S  pkg C0402  page 69 : A = PVDDCR_CPU0_P0 ; B = GND

(kicad_pcb
	(version 20260206)
	(generator "pcbnew")
	(generator_version "10.0")
	(general
		(thickness 1.6)
		(legacy_teardrops no)
	)
	(paper "A4")
	(title_block
		(title "04192023_DAF0TMB3IC0_F0TG_MB_C_brd_V02_OCP.brd")
		(comment 1 "Grand Teton / footprints 7512-7513 of 8354")
	)
	(layers
		(0 "F.Cu" signal "TOP")
		(4 "In1.Cu" signal "GND")
		(6 "In2.Cu" signal "IN1")
		(8 "In3.Cu" signal "GND1")
		(10 "In4.Cu" signal "IN2")
		(12 "In5.Cu" signal "GND2")
		(14 "In6.Cu" signal "IN3")
		(16 "In7.Cu" signal "GND3")
		(18 "In8.Cu" signal "VCC")
		(20 "In9.Cu" signal "VCC1")
		(22 "In10.Cu" signal "GND4")
		(24 "In11.Cu" signal "IN4")
		(26 "In12.Cu" signal "GND5")
		(28 "In13.Cu" signal "IN5")
		(30 "In14.Cu" signal "GND6")
		(32 "In15.Cu" signal "IN6")
		(34 "In16.Cu" signal "GND7")
		(2 "B.Cu" signal "BOTTOM")
		(9 "F.Adhes" user "F.Adhesive")
		(11 "B.Adhes" user "B.Adhesive")
		(13 "F.Paste" user "Package Geometry/Pastemask Top")
		(15 "B.Paste" user "Package Geometry/Pastemask Bottom")
		(5 "F.SilkS" user "Ref Des/Silkscreen Top")
		(7 "B.SilkS" user "Ref Des/Silkscreen Bottom")
		(1 "F.Mask" user "Board Geometry/Soldermask Top")
		(3 "B.Mask" user "Board Geometry/Soldermask Bottom")
		(17 "Dwgs.User" user "User.Drawings")
		(19 "Cmts.User" user "User.Comments")
		(21 "Eco1.User" user "User.Eco1")
		(23 "Eco2.User" user "User.Eco2")
		(25 "Edge.Cuts" user "Board Geometry/Outline")
		(27 "Margin" user)
		(31 "F.CrtYd" user "Package Geometry/Place Bound Top")
		(29 "B.CrtYd" user "Package Geometry/Place Bound Bottom")
		(35 "F.Fab" user "Ref Des/Assembly Top")
		(33 "B.Fab" user "Ref Des/Assembly Bottom")
	)
	(footprint ""
		(layer "B.Cu")
		(at 353.231958 -245.487952)
		(property "Reference" "C245"
			(at 0 0 0)
			(layer "B.SilkS")
			(hide yes)
			(effects
				(font
					(size 1.27 1.27)
				)
				(justify mirror)
			)
		)
		(property "Value" ""
			(at 0 0 0)
			(layer "B.Fab")
			(effects
				(font
					(size 1.27 1.27)
				)
				(justify mirror)
			)
		)
		(duplicate_pad_numbers_are_jumpers no)
		(fp_line
			(start -0.7874 -0.4064)
			(end -0.7874 0.4064)
			(stroke
				(width 0.1524)
				(type default)
			)
			(layer "B.SilkS")
		)
		(fp_line
			(start -0.7874 0.4064)
			(end 0.7874 0.4064)
			(stroke
				(width 0.1524)
				(type default)
			)
			(layer "B.SilkS")
		)
		(fp_line
			(start 0.7874 -0.4064)
			(end -0.7874 -0.4064)
			(stroke
				(width 0.1524)
				(type default)
			)
			(layer "B.SilkS")
		)
		(fp_line
			(start 0.7874 0.4064)
			(end 0.7874 -0.4064)
			(stroke
				(width 0.1524)
				(type default)
			)
			(layer "B.SilkS")
		)
		(fp_line
			(start -0.67945 -0.3048)
			(end -0.67945 0.3048)
			(stroke
				(width 0.1)
				(type default)
			)
			(layer "B.Fab")
		)
		(fp_line
			(start -0.67945 0.3048)
			(end -0.120396 0.3048)
			(stroke
				(width 0.1)
				(type default)
			)
			(layer "B.Fab")
		)
		(fp_line
			(start -0.12065 -0.3048)
			(end -0.67945 -0.3048)
			(stroke
				(width 0.1)
				(type default)
			)
			(layer "B.Fab")
		)
		(fp_line
			(start -0.12065 -0.2794)
			(end -0.12065 -0.3048)
			(stroke
				(width 0.1)
				(type default)
			)
			(layer "B.Fab")
		)
		(fp_line
			(start -0.120396 0.2794)
			(end 0.12065 0.2794)
			(stroke
				(width 0.1)
				(type default)
			)
			(layer "B.Fab")
		)
		(fp_line
			(start -0.120396 0.3048)
			(end -0.120396 0.2794)
			(stroke
				(width 0.1)
				(type default)
			)
			(layer "B.Fab")
		)
		(fp_line
			(start 0.12065 -0.305054)
			(end 0.12065 -0.2794)
			(stroke
				(width 0.1)
				(type default)
			)
			(layer "B.Fab")
		)
		(fp_line
			(start 0.12065 -0.2794)
			(end -0.12065 -0.2794)
			(stroke
				(width 0.1)
				(type default)
			)
			(layer "B.Fab")
		)
		(fp_line
			(start 0.12065 0.2794)
			(end 0.12065 0.3048)
			(stroke
				(width 0.1)
				(type default)
			)
			(layer "B.Fab")
		)
		(fp_line
			(start 0.12065 0.3048)
			(end 0.67945 0.3048)
			(stroke
				(width 0.1)
				(type default)
			)
			(layer "B.Fab")
		)
		(fp_line
			(start 0.67945 -0.305054)
			(end 0.12065 -0.305054)
			(stroke
				(width 0.1)
				(type default)
			)
			(layer "B.Fab")
		)
		(fp_line
			(start 0.67945 0.3048)
			(end 0.67945 -0.305054)
			(stroke
				(width 0.1)
				(type default)
			)
			(layer "B.Fab")
		)
		(pad "1" smd circle
			(at 0.40005 0 180)
			(size 0 0)
			(layers "B.Cu" "B.Mask" "B.Paste")
			(net "PVDDCR_CPU0_P0")
		)
		(pad "2" smd circle
			(at -0.40005 0 180)
			(size 0 0)
			(layers "B.Cu" "B.Mask" "B.Paste")
			(net "GND")
		)
	)
	(footprint ""
		(layer "B.Cu")
		(at 321.391026 -398.942052 90)
		(property "Reference" "C567"
			(at 0 0 90)
			(layer "B.SilkS")
			(hide yes)
			(effects
				(font
					(size 1.27 1.27)
				)
				(justify mirror)
			)
		)
		(property "Value" ""
			(at 0 0 90)
			(layer "B.Fab")
			(effects
				(font
					(size 1.27 1.27)
				)
				(justify mirror)
			)
		)
		(duplicate_pad_numbers_are_jumpers no)
		(fp_line
			(start 0.7874 -0.4064)
			(end -0.7874 -0.4064)
			(stroke
				(width 0.1524)
				(type default)
			)
			(layer "B.SilkS")
		)
		(fp_line
			(start -0.7874 -0.4064)
			(end -0.7874 0.4064)
			(stroke
				(width 0.1524)
				(type default)
			)
			(layer "B.SilkS")
		)
		(fp_line
			(start 0.7874 0.4064)
			(end 0.7874 -0.4064)
			(stroke
				(width 0.1524)
				(type default)
			)
			(layer "B.SilkS")
		)
		(fp_line
			(start -0.7874 0.4064)
			(end 0.7874 0.4064)
			(stroke
				(width 0.1524)
				(type default)
			)
			(layer "B.SilkS")
		)
		(fp_line
			(start 0.67945 -0.305054)
			(end 0.12065 -0.305054)
			(stroke
				(width 0.1)
				(type default)
			)
			(layer "B.Fab")
		)
		(fp_line
			(start 0.12065 -0.305054)
			(end 0.12065 -0.2794)
			(stroke
				(width 0.1)
				(type default)
			)
			(layer "B.Fab")
		)
		(fp_line
			(start -0.12065 -0.3048)
			(end -0.67945 -0.3048)
			(stroke
				(width 0.1)
				(type default)
			)
			(layer "B.Fab")
		)
		(fp_line
			(start -0.67945 -0.3048)
			(end -0.67945 0.3048)
			(stroke
				(width 0.1)
				(type default)
			)
			(layer "B.Fab")
		)
		(fp_line
			(start 0.12065 -0.2794)
			(end -0.12065 -0.2794)
			(stroke
				(width 0.1)
				(type default)
			)
			(layer "B.Fab")
		)
		(fp_line
			(start -0.12065 -0.2794)
			(end -0.12065 -0.3048)
			(stroke
				(width 0.1)
				(type default)
			)
			(layer "B.Fab")
		)
		(fp_line
			(start 0.12065 0.2794)
			(end 0.12065 0.3048)
			(stroke
				(width 0.1)
				(type default)
			)
			(layer "B.Fab")
		)
		(fp_line
			(start -0.120396 0.2794)
			(end 0.12065 0.2794)
			(stroke
				(width 0.1)
				(type default)
			)
			(layer "B.Fab")
		)
		(fp_line
			(start 0.67945 0.3048)
			(end 0.67945 -0.305054)
			(stroke
				(width 0.1)
				(type default)
			)
			(layer "B.Fab")
		)
		(fp_line
			(start 0.12065 0.3048)
			(end 0.67945 0.3048)
			(stroke
				(width 0.1)
				(type default)
			)
			(layer "B.Fab")
		)
		(fp_line
			(start -0.120396 0.3048)
			(end -0.120396 0.2794)
			(stroke
				(width 0.1)
				(type default)
			)
			(layer "B.Fab")
		)
		(fp_line
			(start -0.67945 0.3048)
			(end -0.120396 0.3048)
			(stroke
				(width 0.1)
				(type default)
			)
			(layer "B.Fab")
		)
		(pad "1" smd circle
			(at 0.40005 0 270)
			(size 0 0)
			(layers "B.Cu" "B.Mask" "B.Paste")
			(net "P0V9_CPU0_RT0_2A")
		)
		(pad "2" smd circle
			(at -0.40005 0 270)
			(size 0 0)
			(layers "B.Cu" "B.Mask" "B.Paste")
			(net "GND")
		)
	)
)
